(kicad_pcb
	(version 20260206)
	(generator "pcbnew")
	(generator_version "10.0")
	(general
		(thickness 1.6)
		(legacy_teardrops no)
	)
	(paper "A4")
	(title_block
		(title "Bryce Canyon_R.DPB_16317-1_OCP.brd")
		(comment 1 "Bryce Canyon / footprints 1743-1745 of 2099")
	)
	(layers
		(0 "F.Cu" signal "TOP")
		(4 "In1.Cu" signal "L2GND")
		(6 "In2.Cu" signal "L3")
		(8 "In3.Cu" signal "L4VCC")
		(10 "In4.Cu" signal "L5VCC")
		(12 "In5.Cu" signal "L6")
		(14 "In6.Cu" signal "L7GND")
		(2 "B.Cu" signal "BOTTOM")
		(9 "F.Adhes" user "F.Adhesive")
		(11 "B.Adhes" user "B.Adhesive")
		(13 "F.Paste" user "Package Geometry/Pastemask Top")
		(15 "B.Paste" user "Package Geometry/Pastemask Bottom")
		(5 "F.SilkS" user "Ref Des/Silkscreen Top")
		(7 "B.SilkS" user "Ref Des/Silkscreen Bottom")
		(1 "F.Mask" user "Board Geometry/Soldermask Top")
		(3 "B.Mask" user "Board Geometry/Soldermask Bottom")
		(17 "Dwgs.User" user "User.Drawings")
		(19 "Cmts.User" user "User.Comments")
		(21 "Eco1.User" user "User.Eco1")
		(23 "Eco2.User" user "User.Eco2")
		(25 "Edge.Cuts" user "Board Geometry/Outline")
		(27 "Margin" user)
		(31 "F.CrtYd" user "Package Geometry/Place Bound Top")
		(29 "B.CrtYd" user "Package Geometry/Place Bound Bottom")
		(35 "F.Fab" user "Ref Des/Assembly Top")
		(33 "B.Fab" user "Ref Des/Assembly Bottom")
	)
	(footprint ""
		(layer "F.Cu")
		(at 461.01 -138.938 -90)
		(property "Reference" "Q106"
			(at 0 0 270)
			(layer "F.SilkS")
			(hide yes)
			(effects
				(font
					(size 1.27 1.27)
				)
			)
		)
		(property "Value" "AO4406AL-GP"
			(at -3.707384 -1.5367 270)
			(unlocked yes)
			(layer "F.Fab")
			(hide yes)
			(effects
				(font
					(size 1.016 1.016)
					(thickness 0.1524)
				)
			)
		)
		(property "Device Type" "SOIC8H69"
			(at -3.707384 -3.0607 270)
			(unlocked yes)
			(layer "F.Fab")
			(hide yes)
			(effects
				(font
					(size 1.016 1.016)
					(thickness 0.1524)
				)
			)
		)
		(duplicate_pad_numbers_are_jumpers no)
		(fp_line
			(start -2.6289 3.4417)
			(end -2.6289 1.4732)
			(stroke
				(width 0.381)
				(type default)
			)
			(layer "F.SilkS")
		)
		(fp_line
			(start -2.7432 1.4224)
			(end -2.6416 1.4224)
			(stroke
				(width 0.1524)
				(type default)
			)
			(layer "F.SilkS")
		)
		(fp_line
			(start -2.7432 1.4224)
			(end 2.1336 1.4224)
			(stroke
				(width 0.1524)
				(type default)
			)
			(layer "F.SilkS")
		)
		(fp_line
			(start 2.1336 1.4224)
			(end 2.1336 -1.4224)
			(stroke
				(width 0.1524)
				(type default)
			)
			(layer "F.SilkS")
		)
		(fp_line
			(start -2.1844 -0.0508)
			(end -2.7178 0.508)
			(stroke
				(width 0.1524)
				(type default)
			)
			(layer "F.SilkS")
		)
		(fp_line
			(start -2.7178 -0.508)
			(end -2.1844 -0.0508)
			(stroke
				(width 0.1524)
				(type default)
			)
			(layer "F.SilkS")
		)
		(fp_line
			(start -2.7432 -1.4224)
			(end -2.7432 1.4224)
			(stroke
				(width 0.1524)
				(type default)
			)
			(layer "F.SilkS")
		)
		(fp_line
			(start 2.1336 -1.4224)
			(end -2.7432 -1.4224)
			(stroke
				(width 0.1524)
				(type default)
			)
			(layer "F.SilkS")
		)
		(fp_poly
			(pts
				(xy -2.2098 -1.4224) (xy -2.2098 1.4224) (xy 2.2098 1.4224) (xy 2.2098 -1.4224)
			)
			(stroke
				(width 0)
				(type default)
			)
			(fill yes)
			(layer "F.SilkS")
		)
		(fp_rect
			(start -2.450084 2.999994)
			(end 2.450084 -2.999994)
			(stroke
				(width 0)
				(type default)
			)
			(fill no)
			(layer "F.CrtYd")
		)
		(fp_poly
			(pts
				(xy -2.8194 3.6322) (xy -2.8194 -3.6322) (xy 2.8194 -3.6322) (xy 2.8194 1.18364) (xy 2.450084 1.18364)
				(xy 2.450084 -2.999994) (xy -2.450084 -2.999994) (xy -2.450084 2.999994) (xy 2.450084 2.999994)
				(xy 2.450084 1.18618) (xy 2.8194 1.18618) (xy 2.8194 3.6322)
			)
			(stroke
				(width 0)
				(type default)
			)
			(fill no)
			(layer "F.CrtYd")
		)
		(fp_rect
			(start -2.8194 3.6322)
			(end 2.8194 -3.6322)
			(stroke
				(width 0)
				(type default)
			)
			(fill no)
			(layer "F.Fab")
		)
		(pad "1" smd rect
			(at -1.905 2.54 270)
			(size 0.635 1.651)
			(layers "F.Cu" "F.Mask" "F.Paste")
			(net "P5V_HDD22")
		)
		(pad "2" smd rect
			(at -0.635 2.54 270)
			(size 0.635 1.651)
			(layers "F.Cu" "F.Mask" "F.Paste")
			(net "P5V_HDD22")
		)
		(pad "3" smd rect
			(at 0.635 2.54 270)
			(size 0.635 1.651)
			(layers "F.Cu" "F.Mask" "F.Paste")
			(net "P5V_HDD22")
		)
		(pad "4" smd rect
			(at 1.905 2.54 270)
			(size 0.635 1.651)
			(layers "F.Cu" "F.Mask" "F.Paste")
			(net "SW_HDD_P22")
		)
		(pad "5" smd rect
			(at 1.905 -2.54 270)
			(size 0.635 1.651)
			(layers "F.Cu" "F.Mask" "F.Paste")
			(net "P5V_B_4")
		)
		(pad "6" smd rect
			(at 0.635 -2.54 270)
			(size 0.635 1.651)
			(layers "F.Cu" "F.Mask" "F.Paste")
			(net "P5V_B_4")
		)
		(pad "7" smd rect
			(at -0.635 -2.54 270)
			(size 0.635 1.651)
			(layers "F.Cu" "F.Mask" "F.Paste")
			(net "P5V_B_4")
		)
		(pad "8" smd rect
			(at -1.905 -2.54 270)
			(size 0.635 1.651)
			(layers "F.Cu" "F.Mask" "F.Paste")
			(net "P5V_B_4")
		)
	)
	(footprint ""
		(layer "F.Cu")
		(at 478.9932 -157.226)
		(property "Reference" "C334"
			(at 0 0 0)
			(layer "F.SilkS")
			(hide yes)
			(effects
				(font
					(size 1.27 1.27)
				)
			)
		)
		(property "Value" "SC4D7U25V5KX-1-GP"
			(at -0.0762 -6.1214 0)
			(unlocked yes)
			(layer "F.Fab")
			(hide yes)
			(effects
				(font
					(size 1.016 1.016)
					(thickness 0.1524)
				)
			)
		)
		(property "Device Type" "C805H58"
			(at -0.0762 -8.1534 0)
			(unlocked yes)
			(layer "F.Fab")
			(hide yes)
			(effects
				(font
					(size 1.016 1.016)
					(thickness 0.1524)
				)
			)
		)
		(duplicate_pad_numbers_are_jumpers no)
		(fp_line
			(start 0.635 0)
			(end -0.635 0)
			(stroke
				(width 0.508)
				(type default)
			)
			(layer "F.SilkS")
		)
		(fp_rect
			(start -0.9652 1.778)
			(end 0.9652 -1.778)
			(stroke
				(width 0)
				(type default)
			)
			(fill no)
			(layer "F.CrtYd")
		)
		(fp_poly
			(pts
				(xy -0.9652 -1.778) (xy 0.9652 -1.778) (xy 0.9652 1.778) (xy -0.9652 1.778)
			)
			(stroke
				(width 0)
				(type default)
			)
			(fill no)
			(layer "F.Fab")
		)
		(pad "1" smd rect
			(at 0 -0.9652)
			(size 1.397 1.143)
			(layers "F.Cu" "F.Mask" "F.Paste")
			(net "P12V_HDD23")
		)
		(pad "2" smd rect
			(at 0 0.9652)
			(size 1.397 1.143)
			(layers "F.Cu" "F.Mask" "F.Paste")
			(net "GND")
		)
	)
	(footprint ""
		(layer "F.Cu")
		(at 455.93 -160.401 180)
		(property "Reference" "C323"
			(at 0 0 180)
			(layer "F.SilkS")
			(hide yes)
			(effects
				(font
					(size 1.27 1.27)
				)
			)
		)
		(property "Value" "SC1U25V3KX-GP"
			(at 0 -2.8194 180)
			(unlocked yes)
			(layer "F.Fab")
			(hide yes)
			(effects
				(font
					(size 1.016 1.016)
					(thickness 0.1524)
				)
			)
		)
		(property "Device Type" "C603H36"
			(at 0 -4.3434 180)
			(unlocked yes)
			(layer "F.Fab")
			(hide yes)
			(effects
				(font
					(size 1.016 1.016)
					(thickness 0.1524)
				)
			)
		)
		(duplicate_pad_numbers_are_jumpers no)
		(fp_line
			(start 0.508 0)
			(end -0.508 0)
			(stroke
				(width 0.2032)
				(type default)
			)
			(layer "F.SilkS")
		)
		(fp_rect
			(start -0.5842 1.3335)
			(end 0.5842 -1.3335)
			(stroke
				(width 0)
				(type default)
			)
			(fill no)
			(layer "F.CrtYd")
		)
		(fp_rect
			(start -0.5842 1.3335)
			(end 0.5842 -1.3335)
			(stroke
				(width 0)
				(type default)
			)
			(fill no)
			(layer "F.Fab")
		)
		(pad "1" smd custom
			(at 0 -0.762 180)
			(size 0.2159 0.2159)
			(layers "F.Cu" "F.Mask" "F.Paste")
			(net "P12V_HDD22")
			(options
				(clearance outline)
				(anchor circle)
			)
			(primitives
				(gr_poly
					(pts
						(arc
							(start -0.3302 -0.4318)
							(mid -0.402042 -0.402042)
							(end -0.4318 -0.3302)
						)
						(arc
							(start -0.4318 0.3302)
							(mid -0.402042 0.402042)
							(end -0.3302 0.4318)
						)
						(arc
							(start 0.3302 0.4318)
							(mid 0.402042 0.402042)
							(end 0.4318 0.3302)
						)
						(arc
							(start 0.4318 -0.3302)
							(mid 0.402042 -0.402042)
							(end 0.3302 -0.4318)
						)
					)
					(width 0)
					(fill yes)
				)
			)
		)
		(pad "2" smd custom
			(at 0 0.762 180)
			(size 0.2159 0.2159)
			(layers "F.Cu" "F.Mask" "F.Paste")
			(net "GND")
			(options
				(clearance outline)
				(anchor circle)
			)
			(primitives
				(gr_poly
					(pts
						(arc
							(start -0.3302 -0.4318)
							(mid -0.402042 -0.402042)
							(end -0.4318 -0.3302)
						)
						(arc
							(start -0.4318 0.3302)
							(mid -0.402042 0.402042)
							(end -0.3302 0.4318)
						)
						(arc
							(start 0.3302 0.4318)
							(mid 0.402042 0.402042)
							(end 0.4318 0.3302)
						)
						(arc
							(start 0.4318 -0.3302)
							(mid 0.402042 -0.402042)
							(end 0.3302 -0.4318)
						)
					)
					(width 0)
					(fill yes)
				)
			)
		)
	)
)
